(kicad_pcb
	(version 20260206)
	(generator "pcbnew")
	(generator_version "10.0")
	(general
		(thickness 1.6)
		(legacy_teardrops no)
	)
	(paper "A4")
	(title_block
		(title "12092022_DA0F0TFB6D0_F0T_FAN_BOARD_MP5048_D_brd_v02_OCP.brd")
		(comment 1 "Grand Teton / footprints 128-134 of 924")
	)
	(layers
		(0 "F.Cu" signal "TOP")
		(4 "In1.Cu" signal "GND")
		(6 "In2.Cu" signal "IN1")
		(8 "In3.Cu" signal "IN2")
		(10 "In4.Cu" signal "GND1")
		(2 "B.Cu" signal "BOTTOM")
		(9 "F.Adhes" user "F.Adhesive")
		(11 "B.Adhes" user "B.Adhesive")
		(13 "F.Paste" user "Package Geometry/Pastemask Top")
		(15 "B.Paste" user "Package Geometry/Pastemask Bottom")
		(5 "F.SilkS" user "Ref Des/Silkscreen Top")
		(7 "B.SilkS" user "Ref Des/Silkscreen Bottom")
		(1 "F.Mask" user "Board Geometry/Soldermask Top")
		(3 "B.Mask" user "Board Geometry/Soldermask Bottom")
		(17 "Dwgs.User" user "User.Drawings")
		(19 "Cmts.User" user "User.Comments")
		(21 "Eco1.User" user "User.Eco1")
		(23 "Eco2.User" user "User.Eco2")
		(25 "Edge.Cuts" user "Board Geometry/Outline")
		(27 "Margin" user)
		(31 "F.CrtYd" user "Package Geometry/Place Bound Top")
		(29 "B.CrtYd" user "Package Geometry/Place Bound Bottom")
		(35 "F.Fab" user "Ref Des/Assembly Top")
		(33 "B.Fab" user "Ref Des/Assembly Bottom")
	)
	(footprint ""
		(layer "F.Cu")
		(at 18.415 -185.166)
		(property "Reference" "C1502"
			(at 0 0 0)
			(layer "F.SilkS")
			(hide yes)
			(effects
				(font
					(size 1.27 1.27)
				)
			)
		)
		(property "Value" ""
			(at 0 0 0)
			(layer "F.Fab")
			(effects
				(font
					(size 1.27 1.27)
				)
			)
		)
		(duplicate_pad_numbers_are_jumpers no)
		(fp_line
			(start -0.7874 -0.4064)
			(end 0.7874 -0.4064)
			(stroke
				(width 0.1524)
				(type default)
			)
			(layer "F.SilkS")
		)
		(fp_line
			(start -0.7874 0.4064)
			(end -0.7874 -0.4064)
			(stroke
				(width 0.1524)
				(type default)
			)
			(layer "F.SilkS")
		)
		(fp_line
			(start 0.7874 -0.4064)
			(end 0.7874 0.4064)
			(stroke
				(width 0.1524)
				(type default)
			)
			(layer "F.SilkS")
		)
		(fp_line
			(start 0.7874 0.4064)
			(end -0.7874 0.4064)
			(stroke
				(width 0.1524)
				(type default)
			)
			(layer "F.SilkS")
		)
		(fp_line
			(start -0.67945 -0.305054)
			(end -0.12065 -0.305054)
			(stroke
				(width 0.1)
				(type default)
			)
			(layer "F.Fab")
		)
		(fp_line
			(start -0.67945 0.3048)
			(end -0.67945 -0.305054)
			(stroke
				(width 0.1)
				(type default)
			)
			(layer "F.Fab")
		)
		(fp_line
			(start -0.12065 -0.305054)
			(end -0.12065 -0.2794)
			(stroke
				(width 0.1)
				(type default)
			)
			(layer "F.Fab")
		)
		(fp_line
			(start -0.12065 -0.2794)
			(end 0.12065 -0.2794)
			(stroke
				(width 0.1)
				(type default)
			)
			(layer "F.Fab")
		)
		(fp_line
			(start -0.12065 0.2794)
			(end -0.12065 0.3048)
			(stroke
				(width 0.1)
				(type default)
			)
			(layer "F.Fab")
		)
		(fp_line
			(start -0.12065 0.3048)
			(end -0.67945 0.3048)
			(stroke
				(width 0.1)
				(type default)
			)
			(layer "F.Fab")
		)
		(fp_line
			(start 0.120396 0.2794)
			(end -0.12065 0.2794)
			(stroke
				(width 0.1)
				(type default)
			)
			(layer "F.Fab")
		)
		(fp_line
			(start 0.120396 0.3048)
			(end 0.120396 0.2794)
			(stroke
				(width 0.1)
				(type default)
			)
			(layer "F.Fab")
		)
		(fp_line
			(start 0.12065 -0.3048)
			(end 0.67945 -0.3048)
			(stroke
				(width 0.1)
				(type default)
			)
			(layer "F.Fab")
		)
		(fp_line
			(start 0.12065 -0.2794)
			(end 0.12065 -0.3048)
			(stroke
				(width 0.1)
				(type default)
			)
			(layer "F.Fab")
		)
		(fp_line
			(start 0.67945 -0.3048)
			(end 0.67945 0.3048)
			(stroke
				(width 0.1)
				(type default)
			)
			(layer "F.Fab")
		)
		(fp_line
			(start 0.67945 0.3048)
			(end 0.120396 0.3048)
			(stroke
				(width 0.1)
				(type default)
			)
			(layer "F.Fab")
		)
		(pad "1" smd circle
			(at -0.40005 0)
			(size 0 0)
			(layers "F.Cu" "F.Mask" "F.Paste")
			(net "P3V3_AUX")
		)
		(pad "2" smd circle
			(at 0.40005 0)
			(size 0 0)
			(layers "F.Cu" "F.Mask" "F.Paste")
			(net "GND")
		)
	)
	(footprint ""
		(layer "F.Cu")
		(at 48.768 -221.234 90)
		(property "Reference" "C2024"
			(at 0 0 90)
			(layer "F.SilkS")
			(hide yes)
			(effects
				(font
					(size 1.27 1.27)
				)
			)
		)
		(property "Value" ""
			(at 0 0 90)
			(layer "F.Fab")
			(effects
				(font
					(size 1.27 1.27)
				)
			)
		)
		(duplicate_pad_numbers_are_jumpers no)
		(fp_line
			(start 1.524 -0.762)
			(end 1.524 0.762)
			(stroke
				(width 0.1524)
				(type default)
			)
			(layer "F.SilkS")
		)
		(fp_line
			(start -1.524 -0.762)
			(end 1.524 -0.762)
			(stroke
				(width 0.1524)
				(type default)
			)
			(layer "F.SilkS")
		)
		(fp_line
			(start 1.524 0.762)
			(end -1.524 0.762)
			(stroke
				(width 0.1524)
				(type default)
			)
			(layer "F.SilkS")
		)
		(fp_line
			(start -1.524 0.762)
			(end -1.524 -0.762)
			(stroke
				(width 0.1524)
				(type default)
			)
			(layer "F.SilkS")
		)
		(fp_line
			(start 1.1049 -0.724916)
			(end -1.1049 -0.724916)
			(stroke
				(width 0.1)
				(type default)
			)
			(layer "F.Fab")
		)
		(fp_line
			(start -1.1049 -0.724916)
			(end -1.1049 0.724916)
			(stroke
				(width 0.1)
				(type default)
			)
			(layer "F.Fab")
		)
		(fp_line
			(start 1.1049 0.724916)
			(end 1.1049 -0.724916)
			(stroke
				(width 0.1)
				(type default)
			)
			(layer "F.Fab")
		)
		(fp_line
			(start -1.1049 0.724916)
			(end 1.1049 0.724916)
			(stroke
				(width 0.1)
				(type default)
			)
			(layer "F.Fab")
		)
		(pad "1" smd rect
			(at -0.889 0 270)
			(size 1.016 1.27)
			(layers "F.Cu" "F.Mask" "F.Paste")
			(net "P12V_LED_FAN1")
		)
		(pad "2" smd rect
			(at 0.889 0 270)
			(size 1.016 1.27)
			(layers "F.Cu" "F.Mask" "F.Paste")
			(net "GND")
		)
	)
	(footprint ""
		(layer "F.Cu")
		(at 33.401 -143.891 -90)
		(property "Reference" "R4788"
			(at 0 0 270)
			(layer "F.SilkS")
			(hide yes)
			(effects
				(font
					(size 1.27 1.27)
				)
			)
		)
		(property "Value" ""
			(at 0 0 270)
			(layer "F.Fab")
			(effects
				(font
					(size 1.27 1.27)
				)
			)
		)
		(duplicate_pad_numbers_are_jumpers no)
		(fp_line
			(start -0.7874 0.4064)
			(end -0.7874 -0.4064)
			(stroke
				(width 0.1524)
				(type default)
			)
			(layer "F.SilkS")
		)
		(fp_line
			(start 0.7874 0.4064)
			(end -0.7874 0.4064)
			(stroke
				(width 0.1524)
				(type default)
			)
			(layer "F.SilkS")
		)
		(fp_line
			(start -0.7874 -0.4064)
			(end 0.7874 -0.4064)
			(stroke
				(width 0.1524)
				(type default)
			)
			(layer "F.SilkS")
		)
		(fp_line
			(start 0.7874 -0.4064)
			(end 0.7874 0.4064)
			(stroke
				(width 0.1524)
				(type default)
			)
			(layer "F.SilkS")
		)
		(fp_line
			(start -0.67945 0.3048)
			(end -0.67945 -0.305054)
			(stroke
				(width 0.1)
				(type default)
			)
			(layer "F.Fab")
		)
		(fp_line
			(start -0.12065 0.3048)
			(end -0.67945 0.3048)
			(stroke
				(width 0.1)
				(type default)
			)
			(layer "F.Fab")
		)
		(fp_line
			(start 0.120396 0.3048)
			(end 0.120396 0.2794)
			(stroke
				(width 0.1)
				(type default)
			)
			(layer "F.Fab")
		)
		(fp_line
			(start 0.67945 0.3048)
			(end 0.120396 0.3048)
			(stroke
				(width 0.1)
				(type default)
			)
			(layer "F.Fab")
		)
		(fp_line
			(start -0.12065 0.2794)
			(end -0.12065 0.3048)
			(stroke
				(width 0.1)
				(type default)
			)
			(layer "F.Fab")
		)
		(fp_line
			(start 0.120396 0.2794)
			(end -0.12065 0.2794)
			(stroke
				(width 0.1)
				(type default)
			)
			(layer "F.Fab")
		)
		(fp_line
			(start -0.12065 -0.2794)
			(end 0.12065 -0.2794)
			(stroke
				(width 0.1)
				(type default)
			)
			(layer "F.Fab")
		)
		(fp_line
			(start 0.12065 -0.2794)
			(end 0.12065 -0.3048)
			(stroke
				(width 0.1)
				(type default)
			)
			(layer "F.Fab")
		)
		(fp_line
			(start 0.12065 -0.3048)
			(end 0.67945 -0.3048)
			(stroke
				(width 0.1)
				(type default)
			)
			(layer "F.Fab")
		)
		(fp_line
			(start 0.67945 -0.3048)
			(end 0.67945 0.3048)
			(stroke
				(width 0.1)
				(type default)
			)
			(layer "F.Fab")
		)
		(fp_line
			(start -0.67945 -0.305054)
			(end -0.12065 -0.305054)
			(stroke
				(width 0.1)
				(type default)
			)
			(layer "F.Fab")
		)
		(fp_line
			(start -0.12065 -0.305054)
			(end -0.12065 -0.2794)
			(stroke
				(width 0.1)
				(type default)
			)
			(layer "F.Fab")
		)
		(pad "1" smd circle
			(at -0.40005 0 270)
			(size 0 0)
			(layers "F.Cu" "F.Mask" "F.Paste")
			(net "SMB_FAN3_R_SDA")
		)
		(pad "2" smd circle
			(at 0.40005 0 270)
			(size 0 0)
			(layers "F.Cu" "F.Mask" "F.Paste")
			(net "SMB_FAN3_SDA")
		)
	)
	(footprint ""
		(layer "F.Cu")
		(at 22.86 -23.368 180)
		(property "Reference" "R360"
			(at 0 0 180)
			(layer "F.SilkS")
			(hide yes)
			(effects
				(font
					(size 1.27 1.27)
				)
			)
		)
		(property "Value" ""
			(at 0 0 180)
			(layer "F.Fab")
			(effects
				(font
					(size 1.27 1.27)
				)
			)
		)
		(duplicate_pad_numbers_are_jumpers no)
		(fp_line
			(start 0.7874 0.4064)
			(end -0.7874 0.4064)
			(stroke
				(width 0.1524)
				(type default)
			)
			(layer "F.SilkS")
		)
		(fp_line
			(start 0.7874 -0.4064)
			(end 0.7874 0.4064)
			(stroke
				(width 0.1524)
				(type default)
			)
			(layer "F.SilkS")
		)
		(fp_line
			(start -0.7874 0.4064)
			(end -0.7874 -0.4064)
			(stroke
				(width 0.1524)
				(type default)
			)
			(layer "F.SilkS")
		)
		(fp_line
			(start -0.7874 -0.4064)
			(end 0.7874 -0.4064)
			(stroke
				(width 0.1524)
				(type default)
			)
			(layer "F.SilkS")
		)
		(fp_line
			(start 0.67945 0.3048)
			(end 0.120396 0.3048)
			(stroke
				(width 0.1)
				(type default)
			)
			(layer "F.Fab")
		)
		(fp_line
			(start 0.67945 -0.3048)
			(end 0.67945 0.3048)
			(stroke
				(width 0.1)
				(type default)
			)
			(layer "F.Fab")
		)
		(fp_line
			(start 0.12065 -0.2794)
			(end 0.12065 -0.3048)
			(stroke
				(width 0.1)
				(type default)
			)
			(layer "F.Fab")
		)
		(fp_line
			(start 0.12065 -0.3048)
			(end 0.67945 -0.3048)
			(stroke
				(width 0.1)
				(type default)
			)
			(layer "F.Fab")
		)
		(fp_line
			(start 0.120396 0.3048)
			(end 0.120396 0.2794)
			(stroke
				(width 0.1)
				(type default)
			)
			(layer "F.Fab")
		)
		(fp_line
			(start 0.120396 0.2794)
			(end -0.12065 0.2794)
			(stroke
				(width 0.1)
				(type default)
			)
			(layer "F.Fab")
		)
		(fp_line
			(start -0.12065 0.3048)
			(end -0.67945 0.3048)
			(stroke
				(width 0.1)
				(type default)
			)
			(layer "F.Fab")
		)
		(fp_line
			(start -0.12065 0.2794)
			(end -0.12065 0.3048)
			(stroke
				(width 0.1)
				(type default)
			)
			(layer "F.Fab")
		)
		(fp_line
			(start -0.12065 -0.2794)
			(end 0.12065 -0.2794)
			(stroke
				(width 0.1)
				(type default)
			)
			(layer "F.Fab")
		)
		(fp_line
			(start -0.12065 -0.305054)
			(end -0.12065 -0.2794)
			(stroke
				(width 0.1)
				(type default)
			)
			(layer "F.Fab")
		)
		(fp_line
			(start -0.67945 0.3048)
			(end -0.67945 -0.305054)
			(stroke
				(width 0.1)
				(type default)
			)
			(layer "F.Fab")
		)
		(fp_line
			(start -0.67945 -0.305054)
			(end -0.12065 -0.305054)
			(stroke
				(width 0.1)
				(type default)
			)
			(layer "F.Fab")
		)
		(pad "1" smd circle
			(at -0.40005 0 180)
			(size 0 0)
			(layers "F.Cu" "F.Mask" "F.Paste")
			(net "P3V3_AUX")
		)
		(pad "2" smd circle
			(at 0.40005 0 180)
			(size 0 0)
			(layers "F.Cu" "F.Mask" "F.Paste")
			(net "FAN_3_PWM")
		)
	)
	(footprint ""
		(layer "F.Cu")
		(at 6.477 -167.64)
		(property "Reference" "R102"
			(at 0 0 0)
			(layer "F.SilkS")
			(hide yes)
			(effects
				(font
					(size 1.27 1.27)
				)
			)
		)
		(property "Value" ""
			(at 0 0 0)
			(layer "F.Fab")
			(effects
				(font
					(size 1.27 1.27)
				)
			)
		)
		(duplicate_pad_numbers_are_jumpers no)
		(fp_line
			(start -0.7874 -0.4064)
			(end 0.7874 -0.4064)
			(stroke
				(width 0.1524)
				(type default)
			)
			(layer "F.SilkS")
		)
		(fp_line
			(start -0.7874 0.4064)
			(end -0.7874 -0.4064)
			(stroke
				(width 0.1524)
				(type default)
			)
			(layer "F.SilkS")
		)
		(fp_line
			(start 0.7874 -0.4064)
			(end 0.7874 0.4064)
			(stroke
				(width 0.1524)
				(type default)
			)
			(layer "F.SilkS")
		)
		(fp_line
			(start 0.7874 0.4064)
			(end -0.7874 0.4064)
			(stroke
				(width 0.1524)
				(type default)
			)
			(layer "F.SilkS")
		)
		(fp_line
			(start -0.67945 -0.305054)
			(end -0.12065 -0.305054)
			(stroke
				(width 0.1)
				(type default)
			)
			(layer "F.Fab")
		)
		(fp_line
			(start -0.67945 0.3048)
			(end -0.67945 -0.305054)
			(stroke
				(width 0.1)
				(type default)
			)
			(layer "F.Fab")
		)
		(fp_line
			(start -0.12065 -0.305054)
			(end -0.12065 -0.2794)
			(stroke
				(width 0.1)
				(type default)
			)
			(layer "F.Fab")
		)
		(fp_line
			(start -0.12065 -0.2794)
			(end 0.12065 -0.2794)
			(stroke
				(width 0.1)
				(type default)
			)
			(layer "F.Fab")
		)
		(fp_line
			(start -0.12065 0.2794)
			(end -0.12065 0.3048)
			(stroke
				(width 0.1)
				(type default)
			)
			(layer "F.Fab")
		)
		(fp_line
			(start -0.12065 0.3048)
			(end -0.67945 0.3048)
			(stroke
				(width 0.1)
				(type default)
			)
			(layer "F.Fab")
		)
		(fp_line
			(start 0.120396 0.2794)
			(end -0.12065 0.2794)
			(stroke
				(width 0.1)
				(type default)
			)
			(layer "F.Fab")
		)
		(fp_line
			(start 0.120396 0.3048)
			(end 0.120396 0.2794)
			(stroke
				(width 0.1)
				(type default)
			)
			(layer "F.Fab")
		)
		(fp_line
			(start 0.12065 -0.3048)
			(end 0.67945 -0.3048)
			(stroke
				(width 0.1)
				(type default)
			)
			(layer "F.Fab")
		)
		(fp_line
			(start 0.12065 -0.2794)
			(end 0.12065 -0.3048)
			(stroke
				(width 0.1)
				(type default)
			)
			(layer "F.Fab")
		)
		(fp_line
			(start 0.67945 -0.3048)
			(end 0.67945 0.3048)
			(stroke
				(width 0.1)
				(type default)
			)
			(layer "F.Fab")
		)
		(fp_line
			(start 0.67945 0.3048)
			(end 0.120396 0.3048)
			(stroke
				(width 0.1)
				(type default)
			)
			(layer "F.Fab")
		)
		(pad "1" smd circle
			(at -0.40005 0)
			(size 0 0)
			(layers "F.Cu" "F.Mask" "F.Paste")
			(net "P3V3_AUX")
		)
		(pad "2" smd circle
			(at 0.40005 0)
			(size 0 0)
			(layers "F.Cu" "F.Mask" "F.Paste")
			(net "FAN_3_PRSNT_BUF_R_N")
		)
	)
	(footprint ""
		(layer "F.Cu")
		(at 19.177 -32.004 90)
		(property "Reference" "C2017"
			(at 0 0 90)
			(layer "F.SilkS")
			(hide yes)
			(effects
				(font
					(size 1.27 1.27)
				)
			)
		)
		(property "Value" ""
			(at 0 0 90)
			(layer "F.Fab")
			(effects
				(font
					(size 1.27 1.27)
				)
			)
		)
		(duplicate_pad_numbers_are_jumpers no)
		(fp_line
			(start 0.7874 -0.4064)
			(end 0.7874 0.4064)
			(stroke
				(width 0.1524)
				(type default)
			)
			(layer "F.SilkS")
		)
		(fp_line
			(start -0.7874 -0.4064)
			(end 0.7874 -0.4064)
			(stroke
				(width 0.1524)
				(type default)
			)
			(layer "F.SilkS")
		)
		(fp_line
			(start 0.7874 0.4064)
			(end -0.7874 0.4064)
			(stroke
				(width 0.1524)
				(type default)
			)
			(layer "F.SilkS")
		)
		(fp_line
			(start -0.7874 0.4064)
			(end -0.7874 -0.4064)
			(stroke
				(width 0.1524)
				(type default)
			)
			(layer "F.SilkS")
		)
		(fp_line
			(start -0.12065 -0.305054)
			(end -0.12065 -0.2794)
			(stroke
				(width 0.1)
				(type default)
			)
			(layer "F.Fab")
		)
		(fp_line
			(start -0.67945 -0.305054)
			(end -0.12065 -0.305054)
			(stroke
				(width 0.1)
				(type default)
			)
			(layer "F.Fab")
		)
		(fp_line
			(start 0.67945 -0.3048)
			(end 0.67945 0.3048)
			(stroke
				(width 0.1)
				(type default)
			)
			(layer "F.Fab")
		)
		(fp_line
			(start 0.12065 -0.3048)
			(end 0.67945 -0.3048)
			(stroke
				(width 0.1)
				(type default)
			)
			(layer "F.Fab")
		)
		(fp_line
			(start 0.12065 -0.2794)
			(end 0.12065 -0.3048)
			(stroke
				(width 0.1)
				(type default)
			)
			(layer "F.Fab")
		)
		(fp_line
			(start -0.12065 -0.2794)
			(end 0.12065 -0.2794)
			(stroke
				(width 0.1)
				(type default)
			)
			(layer "F.Fab")
		)
		(fp_line
			(start 0.120396 0.2794)
			(end -0.12065 0.2794)
			(stroke
				(width 0.1)
				(type default)
			)
			(layer "F.Fab")
		)
		(fp_line
			(start -0.12065 0.2794)
			(end -0.12065 0.3048)
			(stroke
				(width 0.1)
				(type default)
			)
			(layer "F.Fab")
		)
		(fp_line
			(start 0.67945 0.3048)
			(end 0.120396 0.3048)
			(stroke
				(width 0.1)
				(type default)
			)
			(layer "F.Fab")
		)
		(fp_line
			(start 0.120396 0.3048)
			(end 0.120396 0.2794)
			(stroke
				(width 0.1)
				(type default)
			)
			(layer "F.Fab")
		)
		(fp_line
			(start -0.12065 0.3048)
			(end -0.67945 0.3048)
			(stroke
				(width 0.1)
				(type default)
			)
			(layer "F.Fab")
		)
		(fp_line
			(start -0.67945 0.3048)
			(end -0.67945 -0.305054)
			(stroke
				(width 0.1)
				(type default)
			)
			(layer "F.Fab")
		)
		(pad "1" smd circle
			(at -0.40005 0 90)
			(size 0 0)
			(layers "F.Cu" "F.Mask" "F.Paste")
			(net "FAN_4_TACH_OL_R")
		)
		(pad "2" smd circle
			(at 0.40005 0 90)
			(size 0 0)
			(layers "F.Cu" "F.Mask" "F.Paste")
			(net "GND")
		)
	)
	(footprint ""
		(layer "F.Cu")
		(at 27.305 -143.891 -90)
		(property "Reference" "R4790"
			(at 0 0 270)
			(layer "F.SilkS")
			(hide yes)
			(effects
				(font
					(size 1.27 1.27)
				)
			)
		)
		(property "Value" ""
			(at 0 0 270)
			(layer "F.Fab")
			(effects
				(font
					(size 1.27 1.27)
				)
			)
		)
		(duplicate_pad_numbers_are_jumpers no)
		(fp_line
			(start -0.7874 0.4064)
			(end -0.7874 -0.4064)
			(stroke
				(width 0.1524)
				(type default)
			)
			(layer "F.SilkS")
		)
		(fp_line
			(start 0.7874 0.4064)
			(end -0.7874 0.4064)
			(stroke
				(width 0.1524)
				(type default)
			)
			(layer "F.SilkS")
		)
		(fp_line
			(start -0.7874 -0.4064)
			(end 0.7874 -0.4064)
			(stroke
				(width 0.1524)
				(type default)
			)
			(layer "F.SilkS")
		)
		(fp_line
			(start 0.7874 -0.4064)
			(end 0.7874 0.4064)
			(stroke
				(width 0.1524)
				(type default)
			)
			(layer "F.SilkS")
		)
		(fp_line
			(start -0.67945 0.3048)
			(end -0.67945 -0.305054)
			(stroke
				(width 0.1)
				(type default)
			)
			(layer "F.Fab")
		)
		(fp_line
			(start -0.12065 0.3048)
			(end -0.67945 0.3048)
			(stroke
				(width 0.1)
				(type default)
			)
			(layer "F.Fab")
		)
		(fp_line
			(start 0.120396 0.3048)
			(end 0.120396 0.2794)
			(stroke
				(width 0.1)
				(type default)
			)
			(layer "F.Fab")
		)
		(fp_line
			(start 0.67945 0.3048)
			(end 0.120396 0.3048)
			(stroke
				(width 0.1)
				(type default)
			)
			(layer "F.Fab")
		)
		(fp_line
			(start -0.12065 0.2794)
			(end -0.12065 0.3048)
			(stroke
				(width 0.1)
				(type default)
			)
			(layer "F.Fab")
		)
		(fp_line
			(start 0.120396 0.2794)
			(end -0.12065 0.2794)
			(stroke
				(width 0.1)
				(type default)
			)
			(layer "F.Fab")
		)
		(fp_line
			(start -0.12065 -0.2794)
			(end 0.12065 -0.2794)
			(stroke
				(width 0.1)
				(type default)
			)
			(layer "F.Fab")
		)
		(fp_line
			(start 0.12065 -0.2794)
			(end 0.12065 -0.3048)
			(stroke
				(width 0.1)
				(type default)
			)
			(layer "F.Fab")
		)
		(fp_line
			(start 0.12065 -0.3048)
			(end 0.67945 -0.3048)
			(stroke
				(width 0.1)
				(type default)
			)
			(layer "F.Fab")
		)
		(fp_line
			(start 0.67945 -0.3048)
			(end 0.67945 0.3048)
			(stroke
				(width 0.1)
				(type default)
			)
			(layer "F.Fab")
		)
		(fp_line
			(start -0.67945 -0.305054)
			(end -0.12065 -0.305054)
			(stroke
				(width 0.1)
				(type default)
			)
			(layer "F.Fab")
		)
		(fp_line
			(start -0.12065 -0.305054)
			(end -0.12065 -0.2794)
			(stroke
				(width 0.1)
				(type default)
			)
			(layer "F.Fab")
		)
		(pad "1" smd circle
			(at -0.40005 0 270)
			(size 0 0)
			(layers "F.Cu" "F.Mask" "F.Paste")
			(net "SMB_FAN1_R_SCL")
		)
		(pad "2" smd circle
			(at 0.40005 0 270)
			(size 0 0)
			(layers "F.Cu" "F.Mask" "F.Paste")
			(net "SMB_FAN1_SCL")
		)
	)
)
